(kicad_pcb
	(version 20260206)
	(generator "pcbnew")
	(generator_version "10.0")
	(general
		(thickness 1.6)
		(legacy_teardrops no)
	)
	(paper "A4")
	(title_block
		(title "Bryce Canyon_IOM_M2_16342-2_OCP.brd")
		(comment 1 "Bryce Canyon / footprints 984-990 of 1146")
	)
	(layers
		(0 "F.Cu" signal "TOP")
		(4 "In1.Cu" signal "L2GND")
		(6 "In2.Cu" signal "L3")
		(8 "In3.Cu" signal "L4VCC")
		(10 "In4.Cu" signal "L5VCC")
		(12 "In5.Cu" signal "L6")
		(14 "In6.Cu" signal "L7GND")
		(2 "B.Cu" signal "BOTTOM")
		(9 "F.Adhes" user "F.Adhesive")
		(11 "B.Adhes" user "B.Adhesive")
		(13 "F.Paste" user "Package Geometry/Pastemask Top")
		(15 "B.Paste" user "Package Geometry/Pastemask Bottom")
		(5 "F.SilkS" user "Ref Des/Silkscreen Top")
		(7 "B.SilkS" user "Ref Des/Silkscreen Bottom")
		(1 "F.Mask" user "Board Geometry/Soldermask Top")
		(3 "B.Mask" user "Board Geometry/Soldermask Bottom")
		(17 "Dwgs.User" user "User.Drawings")
		(19 "Cmts.User" user "User.Comments")
		(21 "Eco1.User" user "User.Eco1")
		(23 "Eco2.User" user "User.Eco2")
		(25 "Edge.Cuts" user "Board Geometry/Outline")
		(27 "Margin" user)
		(31 "F.CrtYd" user "Package Geometry/Place Bound Top")
		(29 "B.CrtYd" user "Package Geometry/Place Bound Bottom")
		(35 "F.Fab" user "Ref Des/Assembly Top")
		(33 "B.Fab" user "Ref Des/Assembly Bottom")
	)
	(footprint ""
		(layer "B.Cu")
		(at 48.14443 -163.240974 90)
		(property "Reference" "R192"
			(at 0 0 90)
			(layer "B.SilkS")
			(hide yes)
			(effects
				(font
					(size 1.27 1.27)
				)
				(justify mirror)
			)
		)
		(property "Value" "2K2R2F-GP"
			(at -0.064008 -3.993896 90)
			(unlocked yes)
			(layer "B.Fab")
			(hide yes)
			(effects
				(font
					(size 1.016 1.016)
					(thickness 0.1524)
				)
				(justify mirror)
			)
		)
		(property "Device Type" "R402H16"
			(at -0.064008 -5.517896 90)
			(unlocked yes)
			(layer "B.Fab")
			(hide yes)
			(effects
				(font
					(size 1.016 1.016)
					(thickness 0.1524)
				)
				(justify mirror)
			)
		)
		(duplicate_pad_numbers_are_jumpers no)
		(fp_line
			(start 0.508 -0.9398)
			(end 0.508 0.9398)
			(stroke
				(width 0.1524)
				(type default)
			)
			(layer "B.SilkS")
		)
		(fp_line
			(start -0.508 -0.9398)
			(end 0.508 -0.9398)
			(stroke
				(width 0.1524)
				(type default)
			)
			(layer "B.SilkS")
		)
		(fp_rect
			(start 0.508 0.9398)
			(end -0.508 -0.9398)
			(stroke
				(width 0)
				(type default)
			)
			(fill no)
			(layer "B.CrtYd")
		)
		(fp_rect
			(start 0.508 0.9398)
			(end -0.508 -0.9398)
			(stroke
				(width 0)
				(type default)
			)
			(fill no)
			(layer "B.Fab")
		)
		(pad "1" smd custom
			(at 0 -0.4445 270)
			(size 0.1397 0.1397)
			(layers "B.Cu" "B.Mask" "B.Paste")
			(net "I2C_MEZZ_OOB_SDA")
			(options
				(clearance outline)
				(anchor circle)
			)
			(primitives
				(gr_poly
					(pts
						(arc
							(start -0.1778 0.2794)
							(mid -0.249642 0.249642)
							(end -0.2794 0.1778)
						)
						(arc
							(start -0.2794 -0.1778)
							(mid -0.249642 -0.249642)
							(end -0.1778 -0.2794)
						)
						(arc
							(start 0.1778 -0.2794)
							(mid 0.249642 -0.249642)
							(end 0.2794 -0.1778)
						)
						(arc
							(start 0.2794 0.1778)
							(mid 0.249642 0.249642)
							(end 0.1778 0.2794)
						)
					)
					(width 0)
					(fill yes)
				)
			)
		)
		(pad "2" smd custom
			(at 0 0.4445 270)
			(size 0.1397 0.1397)
			(layers "B.Cu" "B.Mask" "B.Paste")
			(net "P3V3_STBY")
			(options
				(clearance outline)
				(anchor circle)
			)
			(primitives
				(gr_poly
					(pts
						(arc
							(start -0.1778 0.2794)
							(mid -0.249642 0.249642)
							(end -0.2794 0.1778)
						)
						(arc
							(start -0.2794 -0.1778)
							(mid -0.249642 -0.249642)
							(end -0.1778 -0.2794)
						)
						(arc
							(start 0.1778 -0.2794)
							(mid 0.249642 -0.249642)
							(end 0.2794 -0.1778)
						)
						(arc
							(start 0.2794 0.1778)
							(mid 0.249642 0.249642)
							(end 0.1778 0.2794)
						)
					)
					(width 0)
					(fill yes)
				)
			)
		)
	)
	(footprint ""
		(layer "B.Cu")
		(at 218.568016 -43.445176)
		(property "Reference" "R466"
			(at 0 0 0)
			(layer "B.SilkS")
			(hide yes)
			(effects
				(font
					(size 1.27 1.27)
				)
				(justify mirror)
			)
		)
		(property "Value" "2D7R3-GP"
			(at 0.0254 -2.5146 0)
			(unlocked yes)
			(layer "B.Fab")
			(hide yes)
			(effects
				(font
					(size 1.016 1.016)
					(thickness 0.1524)
				)
				(justify mirror)
			)
		)
		(property "Device Type" "R603H22"
			(at 0.0254 -4.0386 0)
			(unlocked yes)
			(layer "B.Fab")
			(hide yes)
			(effects
				(font
					(size 1.016 1.016)
					(thickness 0.1524)
				)
				(justify mirror)
			)
		)
		(duplicate_pad_numbers_are_jumpers no)
		(fp_line
			(start -0.2032 0)
			(end -0.4826 0)
			(stroke
				(width 0.2032)
				(type default)
			)
			(layer "B.SilkS")
		)
		(fp_line
			(start 0.4826 0)
			(end 0.2032 0)
			(stroke
				(width 0.2032)
				(type default)
			)
			(layer "B.SilkS")
		)
		(fp_rect
			(start 0.5842 1.3335)
			(end -0.5842 -1.3335)
			(stroke
				(width 0)
				(type default)
			)
			(fill no)
			(layer "B.CrtYd")
		)
		(fp_rect
			(start 0.5842 1.3335)
			(end -0.5842 -1.3335)
			(stroke
				(width 0)
				(type default)
			)
			(fill no)
			(layer "B.Fab")
		)
		(pad "1" smd custom
			(at 0 -0.762 180)
			(size 0.2159 0.2159)
			(layers "B.Cu" "B.Mask" "B.Paste")
			(net "P5V_VBST")
			(options
				(clearance outline)
				(anchor circle)
			)
			(primitives
				(gr_poly
					(pts
						(arc
							(start -0.3302 0.4318)
							(mid -0.402042 0.402042)
							(end -0.4318 0.3302)
						)
						(arc
							(start -0.4318 -0.3302)
							(mid -0.402042 -0.402042)
							(end -0.3302 -0.4318)
						)
						(arc
							(start 0.3302 -0.4318)
							(mid 0.402042 -0.402042)
							(end 0.4318 -0.3302)
						)
						(arc
							(start 0.4318 0.3302)
							(mid 0.402042 0.402042)
							(end 0.3302 0.4318)
						)
					)
					(width 0)
					(fill yes)
				)
			)
		)
		(pad "2" smd custom
			(at 0 0.762 180)
			(size 0.2159 0.2159)
			(layers "B.Cu" "B.Mask" "B.Paste")
			(net "P5V_VBST_RC")
			(options
				(clearance outline)
				(anchor circle)
			)
			(primitives
				(gr_poly
					(pts
						(arc
							(start -0.3302 0.4318)
							(mid -0.402042 0.402042)
							(end -0.4318 0.3302)
						)
						(arc
							(start -0.4318 -0.3302)
							(mid -0.402042 -0.402042)
							(end -0.3302 -0.4318)
						)
						(arc
							(start 0.3302 -0.4318)
							(mid 0.402042 -0.402042)
							(end 0.4318 -0.3302)
						)
						(arc
							(start 0.4318 0.3302)
							(mid 0.402042 0.402042)
							(end 0.3302 0.4318)
						)
					)
					(width 0)
					(fill yes)
				)
			)
		)
	)
	(footprint ""
		(layer "B.Cu")
		(at 46.10227 -146.962114)
		(property "Reference" "C108"
			(at 0 0 0)
			(layer "B.SilkS")
			(hide yes)
			(effects
				(font
					(size 1.27 1.27)
				)
				(justify mirror)
			)
		)
		(property "Value" "SC1U16V3KX-5GP"
			(at 0 -2.8194 0)
			(unlocked yes)
			(layer "B.Fab")
			(hide yes)
			(effects
				(font
					(size 1.016 1.016)
					(thickness 0.1524)
				)
				(justify mirror)
			)
		)
		(property "Device Type" "C603H36"
			(at 0 -4.3434 0)
			(unlocked yes)
			(layer "B.Fab")
			(hide yes)
			(effects
				(font
					(size 1.016 1.016)
					(thickness 0.1524)
				)
				(justify mirror)
			)
		)
		(duplicate_pad_numbers_are_jumpers no)
		(fp_line
			(start -0.508 0)
			(end 0.508 0)
			(stroke
				(width 0.2032)
				(type default)
			)
			(layer "B.SilkS")
		)
		(fp_rect
			(start 0.5842 1.3335)
			(end -0.5842 -1.3335)
			(stroke
				(width 0)
				(type default)
			)
			(fill no)
			(layer "B.CrtYd")
		)
		(fp_rect
			(start 0.5842 1.3335)
			(end -0.5842 -1.3335)
			(stroke
				(width 0)
				(type default)
			)
			(fill no)
			(layer "B.Fab")
		)
		(pad "1" smd custom
			(at 0 -0.762 180)
			(size 0.2159 0.2159)
			(layers "B.Cu" "B.Mask" "B.Paste")
			(net "P1V15_STBY")
			(options
				(clearance outline)
				(anchor circle)
			)
			(primitives
				(gr_poly
					(pts
						(arc
							(start -0.3302 0.4318)
							(mid -0.402042 0.402042)
							(end -0.4318 0.3302)
						)
						(arc
							(start -0.4318 -0.3302)
							(mid -0.402042 -0.402042)
							(end -0.3302 -0.4318)
						)
						(arc
							(start 0.3302 -0.4318)
							(mid 0.402042 -0.402042)
							(end 0.4318 -0.3302)
						)
						(arc
							(start 0.4318 0.3302)
							(mid 0.402042 0.402042)
							(end 0.3302 0.4318)
						)
					)
					(width 0)
					(fill yes)
				)
			)
		)
		(pad "2" smd custom
			(at 0 0.762 180)
			(size 0.2159 0.2159)
			(layers "B.Cu" "B.Mask" "B.Paste")
			(net "GND")
			(options
				(clearance outline)
				(anchor circle)
			)
			(primitives
				(gr_poly
					(pts
						(arc
							(start -0.3302 0.4318)
							(mid -0.402042 0.402042)
							(end -0.4318 0.3302)
						)
						(arc
							(start -0.4318 -0.3302)
							(mid -0.402042 -0.402042)
							(end -0.3302 -0.4318)
						)
						(arc
							(start 0.3302 -0.4318)
							(mid 0.402042 -0.402042)
							(end 0.4318 -0.3302)
						)
						(arc
							(start 0.4318 0.3302)
							(mid 0.402042 0.402042)
							(end 0.3302 0.4318)
						)
					)
					(width 0)
					(fill yes)
				)
			)
		)
	)
	(footprint ""
		(layer "B.Cu")
		(at 193.29527 -136.854438 90)
		(property "Reference" "R808"
			(at 0 0 90)
			(layer "B.SilkS")
			(hide yes)
			(effects
				(font
					(size 1.27 1.27)
				)
				(justify mirror)
			)
		)
		(property "Value" "0R2J-2-GP"
			(at -0.064008 -3.993896 90)
			(unlocked yes)
			(layer "B.Fab")
			(hide yes)
			(effects
				(font
					(size 1.016 1.016)
					(thickness 0.1524)
				)
				(justify mirror)
			)
		)
		(property "Device Type" "R402H16"
			(at -0.064008 -5.517896 90)
			(unlocked yes)
			(layer "B.Fab")
			(hide yes)
			(effects
				(font
					(size 1.016 1.016)
					(thickness 0.1524)
				)
				(justify mirror)
			)
		)
		(duplicate_pad_numbers_are_jumpers no)
		(fp_line
			(start 0.508 -0.9398)
			(end 0.508 0.9398)
			(stroke
				(width 0.1524)
				(type default)
			)
			(layer "B.SilkS")
		)
		(fp_line
			(start -0.508 -0.9398)
			(end 0.508 -0.9398)
			(stroke
				(width 0.1524)
				(type default)
			)
			(layer "B.SilkS")
		)
		(fp_rect
			(start 0.508 0.9398)
			(end -0.508 -0.9398)
			(stroke
				(width 0)
				(type default)
			)
			(fill no)
			(layer "B.CrtYd")
		)
		(fp_rect
			(start 0.508 0.9398)
			(end -0.508 -0.9398)
			(stroke
				(width 0)
				(type default)
			)
			(fill no)
			(layer "B.Fab")
		)
		(pad "1" smd custom
			(at 0 -0.4445 270)
			(size 0.1397 0.1397)
			(layers "B.Cu" "B.Mask" "B.Paste")
			(net "M2_1_PRESENT_N")
			(options
				(clearance outline)
				(anchor circle)
			)
			(primitives
				(gr_poly
					(pts
						(arc
							(start -0.1778 0.2794)
							(mid -0.249642 0.249642)
							(end -0.2794 0.1778)
						)
						(arc
							(start -0.2794 -0.1778)
							(mid -0.249642 -0.249642)
							(end -0.1778 -0.2794)
						)
						(arc
							(start 0.1778 -0.2794)
							(mid 0.249642 -0.249642)
							(end 0.2794 -0.1778)
						)
						(arc
							(start 0.2794 0.1778)
							(mid 0.249642 0.249642)
							(end 0.1778 0.2794)
						)
					)
					(width 0)
					(fill yes)
				)
			)
		)
		(pad "2" smd custom
			(at 0 0.4445 270)
			(size 0.1397 0.1397)
			(layers "B.Cu" "B.Mask" "B.Paste")
			(net "M2_1_PRESENT_N_R")
			(options
				(clearance outline)
				(anchor circle)
			)
			(primitives
				(gr_poly
					(pts
						(arc
							(start -0.1778 0.2794)
							(mid -0.249642 0.249642)
							(end -0.2794 0.1778)
						)
						(arc
							(start -0.2794 -0.1778)
							(mid -0.249642 -0.249642)
							(end -0.1778 -0.2794)
						)
						(arc
							(start 0.1778 -0.2794)
							(mid 0.249642 -0.249642)
							(end 0.2794 -0.1778)
						)
						(arc
							(start 0.2794 0.1778)
							(mid 0.249642 0.249642)
							(end 0.1778 0.2794)
						)
					)
					(width 0)
					(fill yes)
				)
			)
		)
	)
	(footprint ""
		(layer "B.Cu")
		(at 47.34814 -156.892752 90)
		(property "Reference" "R324"
			(at 0 0 90)
			(layer "B.SilkS")
			(hide yes)
			(effects
				(font
					(size 1.27 1.27)
				)
				(justify mirror)
			)
		)
		(property "Value" "4K7R2F-GP"
			(at -0.064008 -3.993896 90)
			(unlocked yes)
			(layer "B.Fab")
			(hide yes)
			(effects
				(font
					(size 1.016 1.016)
					(thickness 0.1524)
				)
				(justify mirror)
			)
		)
		(property "Device Type" "R402H16"
			(at -0.064008 -5.517896 90)
			(unlocked yes)
			(layer "B.Fab")
			(hide yes)
			(effects
				(font
					(size 1.016 1.016)
					(thickness 0.1524)
				)
				(justify mirror)
			)
		)
		(duplicate_pad_numbers_are_jumpers no)
		(fp_line
			(start 0.508 -0.9398)
			(end 0.508 0.9398)
			(stroke
				(width 0.1524)
				(type default)
			)
			(layer "B.SilkS")
		)
		(fp_line
			(start -0.508 -0.9398)
			(end 0.508 -0.9398)
			(stroke
				(width 0.1524)
				(type default)
			)
			(layer "B.SilkS")
		)
		(fp_rect
			(start 0.508 0.9398)
			(end -0.508 -0.9398)
			(stroke
				(width 0)
				(type default)
			)
			(fill no)
			(layer "B.CrtYd")
		)
		(fp_rect
			(start 0.508 0.9398)
			(end -0.508 -0.9398)
			(stroke
				(width 0)
				(type default)
			)
			(fill no)
			(layer "B.Fab")
		)
		(pad "1" smd custom
			(at 0 -0.4445 270)
			(size 0.1397 0.1397)
			(layers "B.Cu" "B.Mask" "B.Paste")
			(net "BOARD_REV_2")
			(options
				(clearance outline)
				(anchor circle)
			)
			(primitives
				(gr_poly
					(pts
						(arc
							(start -0.1778 0.2794)
							(mid -0.249642 0.249642)
							(end -0.2794 0.1778)
						)
						(arc
							(start -0.2794 -0.1778)
							(mid -0.249642 -0.249642)
							(end -0.1778 -0.2794)
						)
						(arc
							(start 0.1778 -0.2794)
							(mid 0.249642 -0.249642)
							(end 0.2794 -0.1778)
						)
						(arc
							(start 0.2794 0.1778)
							(mid 0.249642 0.249642)
							(end 0.1778 0.2794)
						)
					)
					(width 0)
					(fill yes)
				)
			)
		)
		(pad "2" smd custom
			(at 0 0.4445 270)
			(size 0.1397 0.1397)
			(layers "B.Cu" "B.Mask" "B.Paste")
			(net "GND")
			(options
				(clearance outline)
				(anchor circle)
			)
			(primitives
				(gr_poly
					(pts
						(arc
							(start -0.1778 0.2794)
							(mid -0.249642 0.249642)
							(end -0.2794 0.1778)
						)
						(arc
							(start -0.2794 -0.1778)
							(mid -0.249642 -0.249642)
							(end -0.1778 -0.2794)
						)
						(arc
							(start 0.1778 -0.2794)
							(mid 0.249642 -0.249642)
							(end 0.2794 -0.1778)
						)
						(arc
							(start 0.2794 0.1778)
							(mid 0.249642 0.249642)
							(end 0.1778 0.2794)
						)
					)
					(width 0)
					(fill yes)
				)
			)
		)
	)
	(footprint ""
		(layer "B.Cu")
		(at 48.8442 -124.9172 180)
		(property "Reference" "R286"
			(at 0 0 0)
			(layer "B.SilkS")
			(hide yes)
			(effects
				(font
					(size 1.27 1.27)
				)
				(justify mirror)
			)
		)
		(property "Value" "0R2J-2-GP"
			(at -0.064008 -3.993896 180)
			(unlocked yes)
			(layer "B.Fab")
			(hide yes)
			(effects
				(font
					(size 1.016 1.016)
					(thickness 0.1524)
				)
				(justify mirror)
			)
		)
		(property "Device Type" "R402H16"
			(at -0.064008 -5.517896 180)
			(unlocked yes)
			(layer "B.Fab")
			(hide yes)
			(effects
				(font
					(size 1.016 1.016)
					(thickness 0.1524)
				)
				(justify mirror)
			)
		)
		(duplicate_pad_numbers_are_jumpers no)
		(fp_line
			(start 0.508 -0.9398)
			(end 0.508 0.9398)
			(stroke
				(width 0.1524)
				(type default)
			)
			(layer "B.SilkS")
		)
		(fp_line
			(start -0.508 -0.9398)
			(end 0.508 -0.9398)
			(stroke
				(width 0.1524)
				(type default)
			)
			(layer "B.SilkS")
		)
		(fp_rect
			(start 0.508 0.9398)
			(end -0.508 -0.9398)
			(stroke
				(width 0)
				(type default)
			)
			(fill no)
			(layer "B.CrtYd")
		)
		(fp_rect
			(start 0.508 0.9398)
			(end -0.508 -0.9398)
			(stroke
				(width 0)
				(type default)
			)
			(fill no)
			(layer "B.Fab")
		)
		(pad "1" smd custom
			(at 0 -0.4445)
			(size 0.1397 0.1397)
			(layers "B.Cu" "B.Mask" "B.Paste")
			(net "SCC_LOC_FULL_PWR_EN")
			(options
				(clearance outline)
				(anchor circle)
			)
			(primitives
				(gr_poly
					(pts
						(arc
							(start -0.1778 0.2794)
							(mid -0.249642 0.249642)
							(end -0.2794 0.1778)
						)
						(arc
							(start -0.2794 -0.1778)
							(mid -0.249642 -0.249642)
							(end -0.1778 -0.2794)
						)
						(arc
							(start 0.1778 -0.2794)
							(mid 0.249642 -0.249642)
							(end 0.2794 -0.1778)
						)
						(arc
							(start 0.2794 0.1778)
							(mid 0.249642 0.249642)
							(end 0.1778 0.2794)
						)
					)
					(width 0)
					(fill yes)
				)
			)
		)
		(pad "2" smd custom
			(at 0 0.4445)
			(size 0.1397 0.1397)
			(layers "B.Cu" "B.Mask" "B.Paste")
			(net "SCC_LOC_FULLPWR_EN")
			(options
				(clearance outline)
				(anchor circle)
			)
			(primitives
				(gr_poly
					(pts
						(arc
							(start -0.1778 0.2794)
							(mid -0.249642 0.249642)
							(end -0.2794 0.1778)
						)
						(arc
							(start -0.2794 -0.1778)
							(mid -0.249642 -0.249642)
							(end -0.1778 -0.2794)
						)
						(arc
							(start 0.1778 -0.2794)
							(mid 0.249642 -0.249642)
							(end 0.2794 -0.1778)
						)
						(arc
							(start 0.2794 0.1778)
							(mid 0.249642 0.249642)
							(end 0.1778 0.2794)
						)
					)
					(width 0)
					(fill yes)
				)
			)
		)
	)
	(footprint ""
		(layer "B.Cu")
		(at 34.404046 -142.938246 180)
		(property "Reference" "C57"
			(at 0 0 0)
			(layer "B.SilkS")
			(hide yes)
			(effects
				(font
					(size 1.27 1.27)
				)
				(justify mirror)
			)
		)
		(property "Value" "SC10U6D3V5KX-4GP"
			(at 0.0762 -6.1214 180)
			(unlocked yes)
			(layer "B.Fab")
			(hide yes)
			(effects
				(font
					(size 1.016 1.016)
					(thickness 0.1524)
				)
				(justify mirror)
			)
		)
		(property "Device Type" "C805H58"
			(at 0.0762 -8.1534 180)
			(unlocked yes)
			(layer "B.Fab")
			(hide yes)
			(effects
				(font
					(size 1.016 1.016)
					(thickness 0.1524)
				)
				(justify mirror)
			)
		)
		(duplicate_pad_numbers_are_jumpers no)
		(fp_line
			(start -0.635 0)
			(end 0.635 0)
			(stroke
				(width 0.508)
				(type default)
			)
			(layer "B.SilkS")
		)
		(fp_rect
			(start 0.9652 1.778)
			(end -0.9652 -1.778)
			(stroke
				(width 0)
				(type default)
			)
			(fill no)
			(layer "B.CrtYd")
		)
		(fp_poly
			(pts
				(xy 0.9652 -1.778) (xy -0.9652 -1.778) (xy -0.9652 1.778) (xy 0.9652 1.778)
			)
			(stroke
				(width 0)
				(type default)
			)
			(fill no)
			(layer "B.Fab")
		)
		(pad "1" smd rect
			(at 0 -0.9652)
			(size 1.397 1.143)
			(layers "B.Cu" "B.Mask" "B.Paste")
			(net "GND")
		)
		(pad "2" smd rect
			(at 0 0.9652)
			(size 1.397 1.143)
			(layers "B.Cu" "B.Mask" "B.Paste")
			(net "P1V2_STBY")
		)
	)
)
